# S9S_MB_2U (Grand Teton) — schematic netlist excerpt (pin names and nets, part order shuffled) for the footprints in the layout excerpt that follows; sources: Cadence DE-HDL packaged netlist, KiCad conversion of 03242023_DA0F0TMBIJ0_F0T_Motherboard_J_brd_V01_OCP.brd

J25  SCONN288_ADR50017P130CC  SCONN288_ADR50017-P130CC IO  pkg DDR288S_1-1VXB  page 106
  VIN_BULK0  = P12V_S3_AUX_CPU1_NVDIMM
  RFU0  = TP_CHE_CPU1_DIMM1_FRU_0
  VIN_MGMT  = P3V3_AUX
  HSCL  = I3C_SPD_DDREFGH_CPU1_LVC1_SCL_R
  HSDA  = I3C_SPD_DDREFGH_CPU1_LVC1_SDA
  VSS0  = GND
  DQ0_A  = M_E_CPU1_SA_DQ<0>
  VSS1  = GND
  DQ1_A  = M_E_CPU1_SA_DQ<1>
  VSS2  = GND
  DQS0_A_T  = M_E_CPU1_SA_DQS_DP<0>
  DQS0_A_C  = M_E_CPU1_SA_DQS_DN<0>
  VSS3  = GND
  DQ4_A  = M_E_CPU1_SA_DQ<4>
  VSS4  = GND
  DQ5_A  = M_E_CPU1_SA_DQ<5>
  VSS5  = GND
  DQ8_A  = M_E_CPU1_SA_DQ<8>
  VSS6  = GND
  DQ9_A  = M_E_CPU1_SA_DQ<9>
  VSS7  = GND
  DQS1_A_T  = M_E_CPU1_SA_DQS_DP<1>
  DQS1_A_C  = M_E_CPU1_SA_DQS_DN<1>
  VSS8  = GND
  DQ12_A  = M_E_CPU1_SA_DQ<12>
  VSS9  = GND
  DQ13_A  = M_E_CPU1_SA_DQ<13>
  VSS10  = GND
  DQ16_A  = M_E_CPU1_SA_DQ<16>
  VSS11  = GND
  DQ17_A  = M_E_CPU1_SA_DQ<17>
  VSS12  = GND
  DQS2_A_T  = M_E_CPU1_SA_DQS_DP<2>
  DQS2_A_C  = M_E_CPU1_SA_DQS_DN<2>
  VSS13  = GND
  DQ20_A  = M_E_CPU1_SA_DQ<20>
  VSS14  = GND
  DQ21_A  = M_E_CPU1_SA_DQ<21>
  VSS15  = GND
  DQ24_A  = M_E_CPU1_SA_DQ<24>
  VSS16  = GND
  DQ25_A  = M_E_CPU1_SA_DQ<25>
  VSS17  = GND
  DQS3_A_T  = M_E_CPU1_SA_DQS_DP<3>
  DQS3_A_C  = M_E_CPU1_SA_DQS_DN<3>
  VSS18  = GND
  DQ28_A  = M_E_CPU1_SA_DQ<28>
  VSS19  = GND
  DQ29_A  = M_E_CPU1_SA_DQ<29>
  VSS20  = GND
  CB0_A  = M_E_CPU1_SA_CB<0>
  VSS21  = GND
  CB1_A  = M_E_CPU1_SA_CB<1>
  VSS22  = GND
  DQS4_A_T  = M_E_CPU1_SA_DQS_DP<4>
  DQS4_A_C  = M_E_CPU1_SA_DQS_DN<4>
  VSS23  = GND
  CB4_A  = M_E_CPU1_SA_CB<4>
  VSS24  = GND
  CB5_A  = M_E_CPU1_SA_CB<5>
  VSS25  = GND
  ALERT_N  = M_E_CPU1_ALERT_N
  VSS26  = GND
  CS0_A_N  = M_E_CPU1_SA_CS_N<0>
  VSS27  = GND
  CA0_A  = M_E_CPU1_SA_CA<0>
  VSS28  = GND
  CA2_A  = M_E_CPU1_SA_CA<2>
  VSS29  = GND
  CA4_A  = M_E_CPU1_SA_CA<4>
  VSS30  = GND
  CA6_A  = M_E_CPU1_SA_CA<6>
  VSS31  = GND
  PAR_A  = M_E_CPU1_SA_PAR
  VSS32  = GND
  CA0_B  = M_E_CPU1_SB_CA<0>
  VSS33  = GND
  CA2_B  = M_E_CPU1_SB_CA<2>
  VSS34  = GND
  CA4_B  = M_E_CPU1_SB_CA<4>
  VSS35  = GND
  CA6_B  = M_E_CPU1_SB_CA<6>
  VSS36  = GND
  CS0_B_N  = M_E_CPU1_SB_CS_N<0>
  VSS37  = GND
  \lbd||rsp_a_n\  = M_E_CPU1_SA_RSP<0>
  \lbs||rsp_b_n\  = M_E_CPU1_SB_RSP<0>
  VSS38  = GND
  CB4_B  = M_E_CPU1_SB_CB<4>
  VSS39  = GND
  CB5_B  = M_E_CPU1_SB_CB<5>
  VSS40  = GND
  \dqs9_b_t||tdqs9_b_t||dbi4_b_n\  = M_E_CPU1_SB_DQS_DP<9>
  \dqs9_b_c||tdqs9_b_c\  = M_E_CPU1_SB_DQS_DN<9>
  VSS41  = GND
  CB0_B  = M_E_CPU1_SB_CB<0>
  VSS42  = GND
  CB1_B  = M_E_CPU1_SB_CB<1>
  VSS43  = GND
  DQ0_B  = M_E_CPU1_SB_DQ<0>
  VSS44  = GND
  DQ1_B  = M_E_CPU1_SB_DQ<1>
  VSS45  = GND
  DQS0_B_T  = M_E_CPU1_SB_DQS_DP<0>
  DQS0_B_C  = M_E_CPU1_SB_DQS_DN<0>
  VSS46  = GND
  DQ4_B  = M_E_CPU1_SB_DQ<4>
  VSS47  = GND
  DQ5_B  = M_E_CPU1_SB_DQ<5>
  VSS48  = GND
  DQ8_B  = M_E_CPU1_SB_DQ<8>
  VSS49  = GND
  DQ9_B  = M_E_CPU1_SB_DQ<9>
  VSS50  = GND
  DQS1_B_T  = M_E_CPU1_SB_DQS_DP<1>
  DQS1_B_C  = M_E_CPU1_SB_DQS_DN<1>
  VSS51  = GND
  DQ12_B  = M_E_CPU1_SB_DQ<12>
  VSS52  = GND
  DQ13_B  = M_E_CPU1_SB_DQ<13>
  VSS53  = GND
  DQ16_B  = M_E_CPU1_SB_DQ<16>
  VSS54  = GND
  DQ17_B  = M_E_CPU1_SB_DQ<17>
  VSS55  = GND
  DQS2_B_T  = M_E_CPU1_SB_DQS_DP<2>
  DQS2_B_C  = M_E_CPU1_SB_DQS_DN<2>
  VSS56  = GND
  DQ20_B  = M_E_CPU1_SB_DQ<20>
  VSS57  = GND
  DQ21_B  = M_E_CPU1_SB_DQ<21>
  VSS58  = GND
  DQ24_B  = M_E_CPU1_SB_DQ<24>
  VSS59  = GND
  DQ25_B  = M_E_CPU1_SB_DQ<25>
  VSS60  = GND
  DQS3_B_T  = M_E_CPU1_SB_DQS_DP<3>
  DQS3_B_C  = M_E_CPU1_SB_DQS_DN<3>
  VSS61  = GND
  DQ28_B  = M_E_CPU1_SB_DQ<28>
  VSS62  = GND
  DQ29_B  = M_E_CPU1_SB_DQ<29>
  VSS63  = GND
  RFU1  = TP_CHE_CPU1_DIMM1_FRU_1
  VIN_BULK1  = P12V_S3_AUX_CPU1_NVDIMM
  VIN_BULK2  = P12V_S3_AUX_CPU1_NVDIMM
  \pwr_good||fail_n\  = PWRGD_CHE_CPU1_DIMM1
  HSA  = PD_CHE_CPU1_DIMM1_SAA
  RFU2  = TP_CHE_CPU1_DIMM1_FRU_2
  RFU3  = TP_CHE_CPU1_DIMM1_FRU_3
  VSS64  = GND
  DQ2_A  = M_E_CPU1_SA_DQ<2>
  VSS65  = GND
  DQ3_A  = M_E_CPU1_SA_DQ<3>
  VSS66  = GND
  \dqs5_a_c||tdqs5_a_c||dqs5_a_t||tdqs5_a_t\  = M_E_CPU1_SA_DQS_DN<5>
  \dqs5_a_t||tdqs5_a_t\  = M_E_CPU1_SA_DQS_DP<5>
  VSS67  = GND
  DQ6_A  = M_E_CPU1_SA_DQ<6>
  VSS68  = GND
  DQ7_A  = M_E_CPU1_SA_DQ<7>
  VSS69  = GND
  DQ10_A  = M_E_CPU1_SA_DQ<10>
  VSS70  = GND
  DQ11_A  = M_E_CPU1_SA_DQ<11>
  VSS71  = GND
  \dqs6_a_c||tdqs6_a_c||dqs6_a_t||tdqs6_a_t\  = M_E_CPU1_SA_DQS_DN<6>
  \dqs6_a_t||tdqs6_a_t\  = M_E_CPU1_SA_DQS_DP<6>
  VSS72  = GND
  DQ14_A  = M_E_CPU1_SA_DQ<14>
  VSS73  = GND
  DQ15_A  = M_E_CPU1_SA_DQ<15>
  VSS74  = GND
  DQ18_A  = M_E_CPU1_SA_DQ<18>
  VSS75  = GND
  DQ19_A  = M_E_CPU1_SA_DQ<19>
  VSS76  = GND
  \dqs7_a_c||tdqs7_a_c\  = M_E_CPU1_SA_DQS_DN<7>
  \dqs7_a_t||tdqs7_a_t\  = M_E_CPU1_SA_DQS_DP<7>
  VSS77  = GND
  DQ22_A  = M_E_CPU1_SA_DQ<22>
  VSS78  = GND
  DQ23_A  = M_E_CPU1_SA_DQ<23>
  VSS79  = GND
  DQ26_A  = M_E_CPU1_SA_DQ<26>
  VSS80  = GND
  DQ27_A  = M_E_CPU1_SA_DQ<27>
  VSS81  = GND
  \dqs8_a_c||tdqs8_a_c\  = M_E_CPU1_SA_DQS_DN<8>
  \dqs8_a_t||tdqs8_a_t\  = M_E_CPU1_SA_DQS_DP<8>
  VSS82  = GND
  DQ30_A  = M_E_CPU1_SA_DQ<30>
  VSS83  = GND
  DQ31_A  = M_E_CPU1_SA_DQ<31>
  VSS84  = GND
  CB2_A  = M_E_CPU1_SA_CB<2>
  VSS85  = GND
  CB3_A  = M_E_CPU1_SA_CB<3>
  VSS86  = GND
  \dqs9_a_c||tdqs9_a_c\  = M_E_CPU1_SA_DQS_DN<9>
  \dqs9_a_t||tdqs9_a_t\  = M_E_CPU1_SA_DQS_DP<9>
  VSS87  = GND
  CB6_A  = M_E_CPU1_SA_CB<6>
  VSS88  = GND
  CB7_A  = M_E_CPU1_SA_CB<7>
  VSS89  = GND
  RESET_N  = RST_M_EF_CPU1_FPGA_N
  VSS90  = GND
  CS1_A_N  = M_E_CPU1_SA_CS_N<1>
  VSS91  = GND
  CA1_A  = M_E_CPU1_SA_CA<1>
  VSS92  = GND
  CA3_A  = M_E_CPU1_SA_CA<3>
  VSS93  = GND
  CA5_A  = M_E_CPU1_SA_CA<5>
  VSS94  = GND
  CK_T  = M_E_CPU1_CLK_DP<0>
  CK_C  = M_E_CPU1_CLK_DN<0>
  VSS95  = GND
  RFU4  = TP_CHE_CPU1_DIMM1_FRU_4
  CA1_B  = M_E_CPU1_SB_CA<1>
  VSS96  = GND
  CA3_B  = M_E_CPU1_SB_CA<3>
  VSS97  = GND
  CA5_B  = M_E_CPU1_SB_CA<5>
  VSS98  = GND
  PAR_B  = M_E_CPU1_SB_PAR
  VSS99  = GND
  CS1_B_N  = M_E_CPU1_SB_CS_N<1>
  VSS100  = GND
  RFU5  = TP_CHE_CPU1_DIMM1_FRU_5
  RFU6  = TP_CHE_CPU1_DIMM1_FRU_6
  VSS101  = GND
  CB6_B  = M_E_CPU1_SB_CB<6>
  VSS102  = GND
  CB7_B  = M_E_CPU1_SB_CB<7>
  VSS103  = GND
  DQS4_B_C  = M_E_CPU1_SB_DQS_DN<4>
  DQS4_B_T  = M_E_CPU1_SB_DQS_DP<4>
  VSS104  = GND
  CB2_B  = M_E_CPU1_SB_CB<2>
  VSS105  = GND
  CB3_B  = M_E_CPU1_SB_CB<3>
  VSS106  = GND
  DQ2_B  = M_E_CPU1_SB_DQ<2>
  VSS107  = GND
  DQ3_B  = M_E_CPU1_SB_DQ<3>
  VSS108  = GND
  \dqs5_b_c||tdqs5_b_c\  = M_E_CPU1_SB_DQS_DN<5>
  \dqs5_b_t||tdqs5_b_t\  = M_E_CPU1_SB_DQS_DP<5>
  VSS109  = GND
  DQ6_B  = M_E_CPU1_SB_DQ<6>
  VSS110  = GND
  DQ7_B  = M_E_CPU1_SB_DQ<7>
  VSS111  = GND
  DQ10_B  = M_E_CPU1_SB_DQ<10>
  VSS112  = GND
  DQ11_B  = M_E_CPU1_SB_DQ<11>
  VSS113  = GND
  \dqs6_b_c||tdqs6_b_c\  = M_E_CPU1_SB_DQS_DN<6>
  \dqs6_b_t||tdqs6_b_t\  = M_E_CPU1_SB_DQS_DP<6>
  VSS114  = GND
  DQ14_B  = M_E_CPU1_SB_DQ<14>
  VSS115  = GND
  DQ15_B  = M_E_CPU1_SB_DQ<15>
  VSS116  = GND
  DQ18_B  = M_E_CPU1_SB_DQ<18>
  VSS117  = GND
  DQ19_B  = M_E_CPU1_SB_DQ<19>
  VSS118  = GND
  \dqs7_b_c||tdqs7_b_c\  = M_E_CPU1_SB_DQS_DN<7>
  \dqs7_b_t||tdqs7_b_t\  = M_E_CPU1_SB_DQS_DP<7>
  VSS119  = GND
  DQ22_B  = M_E_CPU1_SB_DQ<22>
  VSS120  = GND
  DQ23_B  = M_E_CPU1_SB_DQ<23>
  VSS121  = GND
  DQ26_B  = M_E_CPU1_SB_DQ<26>
  VSS122  = GND
  DQ27_B  = M_E_CPU1_SB_DQ<27>
  VSS123  = GND
  \dqs8_b_c||tdqs8_b_c\  = M_E_CPU1_SB_DQS_DN<8>
  \dqs8_b_t||tdqs8_b_t\  = M_E_CPU1_SB_DQS_DP<8>
  VSS124  = GND
  DQ30_B  = M_E_CPU1_SB_DQ<30>
  VSS125  = GND
  DQ31_B  = M_E_CPU1_SB_DQ<31>
  VSS126  = GND
  G1  = GND
  G2  = GND
  G3  = GND

(kicad_pcb
	(version 20260206)
	(generator "pcbnew")
	(generator_version "10.0")
	(general
		(thickness 1.6)
		(legacy_teardrops no)
	)
	(paper "A4")
	(title_block
		(title "03242023_DA0F0TMBIJ0_F0T_Motherboard_J_brd_V01_OCP.brd")
		(comment 1 "Grand Teton / footprint 2539 of 6105 (J25), pads 183-228 of 291")
	)
	(layers
		(0 "F.Cu" signal "TOP")
		(4 "In1.Cu" signal "GND")
		(6 "In2.Cu" signal "IN1")
		(8 "In3.Cu" signal "GND1")
		(10 "In4.Cu" signal "IN2")
		(12 "In5.Cu" signal "GND2")
		(14 "In6.Cu" signal "IN3")
		(16 "In7.Cu" signal "GND3")
		(18 "In8.Cu" signal "VCC")
		(20 "In9.Cu" signal "VCC1")
		(22 "In10.Cu" signal "GND4")
		(24 "In11.Cu" signal "IN4")
		(26 "In12.Cu" signal "GND5")
		(28 "In13.Cu" signal "IN5")
		(30 "In14.Cu" signal "GND6")
		(32 "In15.Cu" signal "IN6")
		(34 "In16.Cu" signal "GND7")
		(2 "B.Cu" signal "BOTTOM")
		(9 "F.Adhes" user "F.Adhesive")
		(11 "B.Adhes" user "B.Adhesive")
		(13 "F.Paste" user "Package Geometry/Pastemask Top")
		(15 "B.Paste" user "Package Geometry/Pastemask Bottom")
		(5 "F.SilkS" user "Ref Des/Silkscreen Top")
		(7 "B.SilkS" user "Ref Des/Silkscreen Bottom")
		(1 "F.Mask" user "Board Geometry/Soldermask Top")
		(3 "B.Mask" user "Board Geometry/Soldermask Bottom")
		(17 "Dwgs.User" user "User.Drawings")
		(19 "Cmts.User" user "User.Comments")
		(21 "Eco1.User" user "User.Eco1")
		(23 "Eco2.User" user "User.Eco2")
		(25 "Edge.Cuts" user "Board Geometry/Outline")
		(27 "Margin" user)
		(31 "F.CrtYd" user "Package Geometry/Place Bound Top")
		(29 "B.CrtYd" user "Package Geometry/Place Bound Bottom")
		(35 "F.Fab" user "Ref Des/Assembly Top")
		(33 "B.Fab" user "Ref Des/Assembly Bottom")
	)
	(footprint ""
		(layer "F.Cu")
		(at 168.40708 -258.091686)
		(property "Reference" "J25"
			(at -3.683 -81.702148 0)
			(unlocked yes)
			(layer "F.SilkS")
			(effects
				(font
					(size 0.7874 0.5842)
					(thickness 0.1524)
				)
				(justify left)
			)
		)
		(property "Value" ""
			(at 0 0 0)
			(layer "F.Fab")
			(effects
				(font
					(size 1.27 1.27)
				)
			)
		)
		(duplicate_pad_numbers_are_jumpers no)
		(pad "183" smd rect
			(at 2.050034 -31.025084 270)
			(size 0.519938 1.4986)
			(layers "F.Cu" "F.Mask" "F.Paste")
			(net "M_E_CPU1_SA_DQ<23>")
		)
		(pad "184" smd rect
			(at 2.050034 -30.174946 270)
			(size 0.519938 1.4986)
			(layers "F.Cu" "F.Mask" "F.Paste")
			(net "GND")
		)
		(pad "185" smd rect
			(at 2.050034 -29.325062 270)
			(size 0.519938 1.4986)
			(layers "F.Cu" "F.Mask" "F.Paste")
			(net "M_E_CPU1_SA_DQ<26>")
		)
		(pad "186" smd rect
			(at 2.050034 -28.474924 270)
			(size 0.519938 1.4986)
			(layers "F.Cu" "F.Mask" "F.Paste")
			(net "GND")
		)
		(pad "187" smd rect
			(at 2.050034 -27.62504 270)
			(size 0.519938 1.4986)
			(layers "F.Cu" "F.Mask" "F.Paste")
			(net "M_E_CPU1_SA_DQ<27>")
		)
		(pad "188" smd rect
			(at 2.050034 -26.774902 270)
			(size 0.519938 1.4986)
			(layers "F.Cu" "F.Mask" "F.Paste")
			(net "GND")
		)
		(pad "189" smd rect
			(at 2.050034 -25.925018 270)
			(size 0.519938 1.4986)
			(layers "F.Cu" "F.Mask" "F.Paste")
			(net "M_E_CPU1_SA_DQS_DN<8>")
		)
		(pad "190" smd rect
			(at 2.050034 -25.07488 270)
			(size 0.519938 1.4986)
			(layers "F.Cu" "F.Mask" "F.Paste")
			(net "M_E_CPU1_SA_DQS_DP<8>")
		)
		(pad "191" smd rect
			(at 2.050034 -24.224996 270)
			(size 0.519938 1.4986)
			(layers "F.Cu" "F.Mask" "F.Paste")
			(net "GND")
		)
		(pad "192" smd rect
			(at 2.050034 -23.375112 270)
			(size 0.519938 1.4986)
			(layers "F.Cu" "F.Mask" "F.Paste")
			(net "M_E_CPU1_SA_DQ<30>")
		)
		(pad "193" smd rect
			(at 2.050034 -22.524974 270)
			(size 0.519938 1.4986)
			(layers "F.Cu" "F.Mask" "F.Paste")
			(net "GND")
		)
		(pad "194" smd rect
			(at 2.050034 -21.67509 270)
			(size 0.519938 1.4986)
			(layers "F.Cu" "F.Mask" "F.Paste")
			(net "M_E_CPU1_SA_DQ<31>")
		)
		(pad "195" smd rect
			(at 2.050034 -20.824952 270)
			(size 0.519938 1.4986)
			(layers "F.Cu" "F.Mask" "F.Paste")
			(net "GND")
		)
		(pad "196" smd rect
			(at 2.050034 -19.975068 270)
			(size 0.519938 1.4986)
			(layers "F.Cu" "F.Mask" "F.Paste")
			(net "M_E_CPU1_SA_CB<2>")
		)
		(pad "197" smd rect
			(at 2.050034 -19.12493 270)
			(size 0.519938 1.4986)
			(layers "F.Cu" "F.Mask" "F.Paste")
			(net "GND")
		)
		(pad "198" smd rect
			(at 2.050034 -18.275046 270)
			(size 0.519938 1.4986)
			(layers "F.Cu" "F.Mask" "F.Paste")
			(net "M_E_CPU1_SA_CB<3>")
		)
		(pad "199" smd rect
			(at 2.050034 -17.424908 270)
			(size 0.519938 1.4986)
			(layers "F.Cu" "F.Mask" "F.Paste")
			(net "GND")
		)
		(pad "200" smd rect
			(at 2.050034 -16.575024 270)
			(size 0.519938 1.4986)
			(layers "F.Cu" "F.Mask" "F.Paste")
			(net "M_E_CPU1_SA_DQS_DN<9>")
		)
		(pad "201" smd rect
			(at 2.050034 -15.724886 270)
			(size 0.519938 1.4986)
			(layers "F.Cu" "F.Mask" "F.Paste")
			(net "M_E_CPU1_SA_DQS_DP<9>")
		)
		(pad "202" smd rect
			(at 2.050034 -14.875002 270)
			(size 0.519938 1.4986)
			(layers "F.Cu" "F.Mask" "F.Paste")
			(net "GND")
		)
		(pad "203" smd rect
			(at 2.050034 -14.025118 270)
			(size 0.519938 1.4986)
			(layers "F.Cu" "F.Mask" "F.Paste")
			(net "M_E_CPU1_SA_CB<6>")
		)
		(pad "204" smd rect
			(at 2.050034 -13.17498 270)
			(size 0.519938 1.4986)
			(layers "F.Cu" "F.Mask" "F.Paste")
			(net "GND")
		)
		(pad "205" smd rect
			(at 2.050034 -12.325096 270)
			(size 0.519938 1.4986)
			(layers "F.Cu" "F.Mask" "F.Paste")
			(net "M_E_CPU1_SA_CB<7>")
		)
		(pad "206" smd rect
			(at 2.050034 -11.474958 270)
			(size 0.519938 1.4986)
			(layers "F.Cu" "F.Mask" "F.Paste")
			(net "GND")
		)
		(pad "207" smd rect
			(at 2.050034 -10.625074 270)
			(size 0.519938 1.4986)
			(layers "F.Cu" "F.Mask" "F.Paste")
			(net "RST_M_EF_CPU1_FPGA_N")
		)
		(pad "208" smd rect
			(at 2.050034 -9.774936 270)
			(size 0.519938 1.4986)
			(layers "F.Cu" "F.Mask" "F.Paste")
			(net "GND")
		)
		(pad "209" smd rect
			(at 2.050034 -8.925052 270)
			(size 0.519938 1.4986)
			(layers "F.Cu" "F.Mask" "F.Paste")
			(net "M_E_CPU1_SA_CS_N<1>")
		)
		(pad "210" smd rect
			(at 2.050034 -8.074914 270)
			(size 0.519938 1.4986)
			(layers "F.Cu" "F.Mask" "F.Paste")
			(net "GND")
		)
		(pad "211" smd rect
			(at 2.050034 -7.22503 270)
			(size 0.519938 1.4986)
			(layers "F.Cu" "F.Mask" "F.Paste")
			(net "M_E_CPU1_SA_CA<1>")
		)
		(pad "212" smd rect
			(at 2.050034 -6.374892 270)
			(size 0.519938 1.4986)
			(layers "F.Cu" "F.Mask" "F.Paste")
			(net "GND")
		)
		(pad "213" smd rect
			(at 2.050034 -5.525008 270)
			(size 0.519938 1.4986)
			(layers "F.Cu" "F.Mask" "F.Paste")
			(net "M_E_CPU1_SA_CA<3>")
		)
		(pad "214" smd rect
			(at 2.050034 -4.675124 270)
			(size 0.519938 1.4986)
			(layers "F.Cu" "F.Mask" "F.Paste")
			(net "GND")
		)
		(pad "215" smd rect
			(at 2.050034 -3.824986 270)
			(size 0.519938 1.4986)
			(layers "F.Cu" "F.Mask" "F.Paste")
			(net "M_E_CPU1_SA_CA<5>")
		)
		(pad "216" smd rect
			(at 2.050034 -2.975102 270)
			(size 0.519938 1.4986)
			(layers "F.Cu" "F.Mask" "F.Paste")
			(net "GND")
		)
		(pad "217" smd rect
			(at 2.050034 -2.124964 270)
			(size 0.519938 1.4986)
			(layers "F.Cu" "F.Mask" "F.Paste")
			(net "M_E_CPU1_CLK_DP<0>")
		)
		(pad "218" smd rect
			(at 2.050034 -1.27508 270)
			(size 0.519938 1.4986)
			(layers "F.Cu" "F.Mask" "F.Paste")
			(net "M_E_CPU1_CLK_DN<0>")
		)
		(pad "219" smd rect
			(at 2.050034 -0.424942 270)
			(size 0.519938 1.4986)
			(layers "F.Cu" "F.Mask" "F.Paste")
			(net "GND")
		)
		(pad "220" smd rect
			(at 2.050034 5.525008 270)
			(size 0.519938 1.4986)
			(layers "F.Cu" "F.Mask" "F.Paste")
			(net "TP_CHE_CPU1_DIMM1_FRU_4")
		)
		(pad "221" smd rect
			(at 2.050034 6.374892 270)
			(size 0.519938 1.4986)
			(layers "F.Cu" "F.Mask" "F.Paste")
			(net "M_E_CPU1_SB_CA<1>")
		)
		(pad "222" smd rect
			(at 2.050034 7.22503 270)
			(size 0.519938 1.4986)
			(layers "F.Cu" "F.Mask" "F.Paste")
			(net "GND")
		)
		(pad "223" smd rect
			(at 2.050034 8.074914 270)
			(size 0.519938 1.4986)
			(layers "F.Cu" "F.Mask" "F.Paste")
			(net "M_E_CPU1_SB_CA<3>")
		)
		(pad "224" smd rect
			(at 2.050034 8.925052 270)
			(size 0.519938 1.4986)
			(layers "F.Cu" "F.Mask" "F.Paste")
			(net "GND")
		)
		(pad "225" smd rect
			(at 2.050034 9.774936 270)
			(size 0.519938 1.4986)
			(layers "F.Cu" "F.Mask" "F.Paste")
			(net "M_E_CPU1_SB_CA<5>")
		)
		(pad "226" smd rect
			(at 2.050034 10.625074 270)
			(size 0.519938 1.4986)
			(layers "F.Cu" "F.Mask" "F.Paste")
			(net "GND")
		)
		(pad "227" smd rect
			(at 2.050034 11.474958 270)
			(size 0.519938 1.4986)
			(layers "F.Cu" "F.Mask" "F.Paste")
			(net "M_E_CPU1_SB_PAR")
		)
		(pad "228" smd rect
			(at 2.050034 12.325096 270)
			(size 0.519938 1.4986)
			(layers "F.Cu" "F.Mask" "F.Paste")
			(net "GND")
		)
	)
)
